(kicad_pcb
	(version 20260206)
	(generator "pcbnew")
	(generator_version "10.0")
	(general
		(thickness 1.5755)
		(legacy_teardrops no)
	)
	(paper "A4")
	(title_block
		(title "gnss-neo-m9n — 844-XXXXX_FAB_NEO-M9N_MODULE.PcbDoc")
		(comment 1 "Time Appliance Project (Time Card) / footprints 32-33 of 33")
	)
	(layers
		(0 "F.Cu" signal "L01-Top Layer")
		(4 "In1.Cu" signal "L02-Inner Layer")
		(6 "In2.Cu" signal "L03-Inner Layer")
		(2 "B.Cu" signal "L04-Bottom Layer")
		(9 "F.Adhes" user "F.Adhesive")
		(11 "B.Adhes" user "B.Adhesive")
		(13 "F.Paste" user "Top Paste")
		(15 "B.Paste" user "Bottom Paste")
		(5 "F.SilkS" user "Top Overlay")
		(7 "B.SilkS" user "Bottom Overlay")
		(1 "F.Mask" user "Top Solder")
		(3 "B.Mask" user "Bottom Solder")
		(17 "Dwgs.User" user "User.Drawings")
		(19 "Cmts.User" user "User.Comments")
		(21 "Eco1.User" user "User.Eco1")
		(23 "Eco2.User" user "User.Eco2")
		(25 "Edge.Cuts" user)
		(27 "Margin" user)
		(31 "F.CrtYd" user "Top Courtyard")
		(29 "B.CrtYd" user "Bottom Courtyard")
		(35 "F.Fab" user "Top Component Outline")
		(33 "B.Fab" user "Bottom Component Outline 2")
		(39 "User.1" user "M01_PCB_Outline")
	)
	(footprint "MyLibrary:c0402"
		(layer "F.Cu")
		(at 150.1151 114.176095 90)
		(property "Reference" "C1"
			(at -2.977795 -0.022443 270)
			(unlocked yes)
			(layer "F.SilkS")
			(effects
				(font
					(size 0.635 0.635)
					(thickness 0.1778)
				)
			)
		)
		(property "Value" "1uF 6V3 0402"
			(at 4.3037 2.118183 90)
			(unlocked yes)
			(layer "F.SilkS")
			(hide yes)
			(effects
				(font
					(size 0.635 0.635)
					(thickness 0.1778)
				)
			)
		)
		(sheetname "846-XXXXX_SCH_NEO-M9N_MODULE_2_RECEIVER")
		(sheetfile "846-XXXXX_SCH_NEO-M9N_MODULE_2_RECEIVER.kicad_sch")
		(duplicate_pad_numbers_are_jumpers no)
		(fp_line
			(start 0.9906 -0.4826)
			(end 0.9906 0.4826)
			(stroke
				(width 0.1778)
				(type solid)
			)
			(layer "F.SilkS")
		)
		(fp_line
			(start -0.9906 -0.4826)
			(end 0.9906 -0.4826)
			(stroke
				(width 0.1778)
				(type solid)
			)
			(layer "F.SilkS")
		)
		(fp_line
			(start -0.9906 -0.4826)
			(end -0.9906 0.4826)
			(stroke
				(width 0.1778)
				(type solid)
			)
			(layer "F.SilkS")
		)
		(fp_line
			(start -0.9906 0.4826)
			(end 0.9906 0.4826)
			(stroke
				(width 0.1778)
				(type solid)
			)
			(layer "F.SilkS")
		)
		(pad "1" smd rect
			(at -0.5 0 90)
			(size 0.5 0.5)
			(layers "F.Cu" "F.Mask" "F.Paste")
			(net "GND")
		)
		(pad "2" smd rect
			(at 0.5 0 90)
			(size 0.5 0.5)
			(layers "F.Cu" "F.Mask" "F.Paste")
			(net "+3V3")
		)
	)
	(footprint "MyLibrary:r0402"
		(layer "F.Cu")
		(at 173.42105 101.376095 -90)
		(property "Reference" "R5"
			(at 1.622443 -0.171845 0)
			(unlocked yes)
			(layer "F.SilkS")
			(effects
				(font
					(size 0.635 0.635)
					(thickness 0.1778)
				)
			)
		)
		(property "Value" "0 ohm 0402"
			(at 2.907155 2.168993 270)
			(unlocked yes)
			(layer "F.SilkS")
			(hide yes)
			(effects
				(font
					(size 0.635 0.635)
					(thickness 0.1778)
				)
			)
		)
		(sheetname "846-XXXXX_SCH_NEO-M9N_MODULE_2_RECEIVER")
		(sheetfile "846-XXXXX_SCH_NEO-M9N_MODULE_2_RECEIVER.kicad_sch")
		(duplicate_pad_numbers_are_jumpers no)
		(fp_line
			(start -0.9906 0.5334)
			(end -0.9906 -0.5334)
			(stroke
				(width 0.1778)
				(type solid)
			)
			(layer "F.SilkS")
		)
		(fp_line
			(start 0.9906 0.5334)
			(end -0.9906 0.5334)
			(stroke
				(width 0.1778)
				(type solid)
			)
			(layer "F.SilkS")
		)
		(fp_line
			(start 0.9906 0.5334)
			(end 0.9906 -0.5334)
			(stroke
				(width 0.1778)
				(type solid)
			)
			(layer "F.SilkS")
		)
		(fp_line
			(start 0.9906 -0.5334)
			(end -0.9906 -0.5334)
			(stroke
				(width 0.1778)
				(type solid)
			)
			(layer "F.SilkS")
		)
		(pad "1" smd rect
			(at -0.5 0 270)
			(size 0.5 0.6)
			(layers "F.Cu" "F.Mask" "F.Paste")
			(net "RX_GPS")
		)
		(pad "2" smd rect
			(at 0.5 0 270)
			(size 0.5 0.6)
			(layers "F.Cu" "F.Mask" "F.Paste")
			(net "RX_GPS_CONN")
		)
	)
)
